# S9S_MB_2U (Grand Teton) — schematic netlist excerpt (pin names and nets, part order shuffled) for the footprints in the layout excerpt that follows; sources: Cadence DE-HDL packaged netlist, KiCad conversion of 03242023_DA0F0TMBIJ0_F0T_Motherboard_J_brd_V01_OCP.brd

C535  Q_CAP  22UF 16V 20% X6S  pkg C0805  page 257 : A = PGPPA_AUX ; B = GND
R338  Q_RES  0 5% CHIP  pkg 0402LF  page 225 : A = H_CPU_ERR0_LVC1_R_N ; B = H_CPU_ERR0_LVC1_N
PC1194  Q_CAP  1UF 16V 10% X6S  pkg C0402  page 284 : A = PVCCIN_CPU1_VREF ; B = GND

(kicad_pcb
	(version 20260206)
	(generator "pcbnew")
	(generator_version "10.0")
	(general
		(thickness 1.6)
		(legacy_teardrops no)
	)
	(paper "A4")
	(title_block
		(title "03242023_DA0F0TMBIJ0_F0T_Motherboard_J_brd_V01_OCP.brd")
		(comment 1 "Grand Teton / footprints 259-261 of 6105")
	)
	(layers
		(0 "F.Cu" signal "TOP")
		(4 "In1.Cu" signal "GND")
		(6 "In2.Cu" signal "IN1")
		(8 "In3.Cu" signal "GND1")
		(10 "In4.Cu" signal "IN2")
		(12 "In5.Cu" signal "GND2")
		(14 "In6.Cu" signal "IN3")
		(16 "In7.Cu" signal "GND3")
		(18 "In8.Cu" signal "VCC")
		(20 "In9.Cu" signal "VCC1")
		(22 "In10.Cu" signal "GND4")
		(24 "In11.Cu" signal "IN4")
		(26 "In12.Cu" signal "GND5")
		(28 "In13.Cu" signal "IN5")
		(30 "In14.Cu" signal "GND6")
		(32 "In15.Cu" signal "IN6")
		(34 "In16.Cu" signal "GND7")
		(2 "B.Cu" signal "BOTTOM")
		(9 "F.Adhes" user "F.Adhesive")
		(11 "B.Adhes" user "B.Adhesive")
		(13 "F.Paste" user "Package Geometry/Pastemask Top")
		(15 "B.Paste" user "Package Geometry/Pastemask Bottom")
		(5 "F.SilkS" user "Ref Des/Silkscreen Top")
		(7 "B.SilkS" user "Ref Des/Silkscreen Bottom")
		(1 "F.Mask" user "Board Geometry/Soldermask Top")
		(3 "B.Mask" user "Board Geometry/Soldermask Bottom")
		(17 "Dwgs.User" user "User.Drawings")
		(19 "Cmts.User" user "User.Comments")
		(21 "Eco1.User" user "User.Eco1")
		(23 "Eco2.User" user "User.Eco2")
		(25 "Edge.Cuts" user "Board Geometry/Outline")
		(27 "Margin" user)
		(31 "F.CrtYd" user "Package Geometry/Place Bound Top")
		(29 "B.CrtYd" user "Package Geometry/Place Bound Bottom")
		(35 "F.Fab" user "Ref Des/Assembly Top")
		(33 "B.Fab" user "Ref Des/Assembly Bottom")
	)
	(footprint ""
		(layer "F.Cu")
		(at 139.2682 -104.116378 -90)
		(property "Reference" "R338"
			(at 0 0 270)
			(layer "F.SilkS")
			(hide yes)
			(effects
				(font
					(size 1.27 1.27)
				)
			)
		)
		(property "Value" ""
			(at 0 0 270)
			(layer "F.Fab")
			(effects
				(font
					(size 1.27 1.27)
				)
			)
		)
		(duplicate_pad_numbers_are_jumpers no)
		(fp_line
			(start -0.7874 0.4064)
			(end -0.7874 -0.4064)
			(stroke
				(width 0.1524)
				(type default)
			)
			(layer "F.SilkS")
		)
		(fp_line
			(start 0.7874 0.4064)
			(end -0.7874 0.4064)
			(stroke
				(width 0.1524)
				(type default)
			)
			(layer "F.SilkS")
		)
		(fp_line
			(start -0.7874 -0.4064)
			(end 0.7874 -0.4064)
			(stroke
				(width 0.1524)
				(type default)
			)
			(layer "F.SilkS")
		)
		(fp_line
			(start 0.7874 -0.4064)
			(end 0.7874 0.4064)
			(stroke
				(width 0.1524)
				(type default)
			)
			(layer "F.SilkS")
		)
		(fp_line
			(start -0.67945 0.3048)
			(end -0.67945 -0.305054)
			(stroke
				(width 0.1)
				(type default)
			)
			(layer "F.Fab")
		)
		(fp_line
			(start -0.12065 0.3048)
			(end -0.67945 0.3048)
			(stroke
				(width 0.1)
				(type default)
			)
			(layer "F.Fab")
		)
		(fp_line
			(start 0.120396 0.3048)
			(end 0.120396 0.2794)
			(stroke
				(width 0.1)
				(type default)
			)
			(layer "F.Fab")
		)
		(fp_line
			(start 0.67945 0.3048)
			(end 0.120396 0.3048)
			(stroke
				(width 0.1)
				(type default)
			)
			(layer "F.Fab")
		)
		(fp_line
			(start -0.12065 0.2794)
			(end -0.12065 0.3048)
			(stroke
				(width 0.1)
				(type default)
			)
			(layer "F.Fab")
		)
		(fp_line
			(start 0.120396 0.2794)
			(end -0.12065 0.2794)
			(stroke
				(width 0.1)
				(type default)
			)
			(layer "F.Fab")
		)
		(fp_line
			(start -0.12065 -0.2794)
			(end 0.12065 -0.2794)
			(stroke
				(width 0.1)
				(type default)
			)
			(layer "F.Fab")
		)
		(fp_line
			(start 0.12065 -0.2794)
			(end 0.12065 -0.3048)
			(stroke
				(width 0.1)
				(type default)
			)
			(layer "F.Fab")
		)
		(fp_line
			(start 0.12065 -0.3048)
			(end 0.67945 -0.3048)
			(stroke
				(width 0.1)
				(type default)
			)
			(layer "F.Fab")
		)
		(fp_line
			(start 0.67945 -0.3048)
			(end 0.67945 0.3048)
			(stroke
				(width 0.1)
				(type default)
			)
			(layer "F.Fab")
		)
		(fp_line
			(start -0.67945 -0.305054)
			(end -0.12065 -0.305054)
			(stroke
				(width 0.1)
				(type default)
			)
			(layer "F.Fab")
		)
		(fp_line
			(start -0.12065 -0.305054)
			(end -0.12065 -0.2794)
			(stroke
				(width 0.1)
				(type default)
			)
			(layer "F.Fab")
		)
		(pad "1" smd circle
			(at -0.40005 0 270)
			(size 0 0)
			(layers "F.Cu" "F.Mask" "F.Paste")
			(net "H_CPU_ERR0_LVC1_R_N")
		)
		(pad "2" smd circle
			(at 0.40005 0 270)
			(size 0 0)
			(layers "F.Cu" "F.Mask" "F.Paste")
			(net "H_CPU_ERR0_LVC1_N")
		)
	)
	(footprint ""
		(layer "F.Cu")
		(at 113.349532 -365.158274 90)
		(property "Reference" "PC1194"
			(at 0 0 90)
			(layer "F.SilkS")
			(hide yes)
			(effects
				(font
					(size 1.27 1.27)
				)
			)
		)
		(property "Value" ""
			(at 0 0 90)
			(layer "F.Fab")
			(effects
				(font
					(size 1.27 1.27)
				)
			)
		)
		(duplicate_pad_numbers_are_jumpers no)
		(fp_line
			(start 0.7874 -0.4064)
			(end 0.7874 0.4064)
			(stroke
				(width 0.1524)
				(type default)
			)
			(layer "F.SilkS")
		)
		(fp_line
			(start -0.7874 -0.4064)
			(end 0.7874 -0.4064)
			(stroke
				(width 0.1524)
				(type default)
			)
			(layer "F.SilkS")
		)
		(fp_line
			(start 0.7874 0.4064)
			(end -0.7874 0.4064)
			(stroke
				(width 0.1524)
				(type default)
			)
			(layer "F.SilkS")
		)
		(fp_line
			(start -0.7874 0.4064)
			(end -0.7874 -0.4064)
			(stroke
				(width 0.1524)
				(type default)
			)
			(layer "F.SilkS")
		)
		(fp_line
			(start -0.12065 -0.305054)
			(end -0.12065 -0.2794)
			(stroke
				(width 0.1)
				(type default)
			)
			(layer "F.Fab")
		)
		(fp_line
			(start -0.67945 -0.305054)
			(end -0.12065 -0.305054)
			(stroke
				(width 0.1)
				(type default)
			)
			(layer "F.Fab")
		)
		(fp_line
			(start 0.67945 -0.3048)
			(end 0.67945 0.3048)
			(stroke
				(width 0.1)
				(type default)
			)
			(layer "F.Fab")
		)
		(fp_line
			(start 0.12065 -0.3048)
			(end 0.67945 -0.3048)
			(stroke
				(width 0.1)
				(type default)
			)
			(layer "F.Fab")
		)
		(fp_line
			(start 0.12065 -0.2794)
			(end 0.12065 -0.3048)
			(stroke
				(width 0.1)
				(type default)
			)
			(layer "F.Fab")
		)
		(fp_line
			(start -0.12065 -0.2794)
			(end 0.12065 -0.2794)
			(stroke
				(width 0.1)
				(type default)
			)
			(layer "F.Fab")
		)
		(fp_line
			(start 0.120396 0.2794)
			(end -0.12065 0.2794)
			(stroke
				(width 0.1)
				(type default)
			)
			(layer "F.Fab")
		)
		(fp_line
			(start -0.12065 0.2794)
			(end -0.12065 0.3048)
			(stroke
				(width 0.1)
				(type default)
			)
			(layer "F.Fab")
		)
		(fp_line
			(start 0.67945 0.3048)
			(end 0.120396 0.3048)
			(stroke
				(width 0.1)
				(type default)
			)
			(layer "F.Fab")
		)
		(fp_line
			(start 0.120396 0.3048)
			(end 0.120396 0.2794)
			(stroke
				(width 0.1)
				(type default)
			)
			(layer "F.Fab")
		)
		(fp_line
			(start -0.12065 0.3048)
			(end -0.67945 0.3048)
			(stroke
				(width 0.1)
				(type default)
			)
			(layer "F.Fab")
		)
		(fp_line
			(start -0.67945 0.3048)
			(end -0.67945 -0.305054)
			(stroke
				(width 0.1)
				(type default)
			)
			(layer "F.Fab")
		)
		(pad "1" smd circle
			(at -0.40005 0 90)
			(size 0 0)
			(layers "F.Cu" "F.Mask" "F.Paste")
			(net "PVCCIN_CPU1_VREF")
		)
		(pad "2" smd circle
			(at 0.40005 0 90)
			(size 0 0)
			(layers "F.Cu" "F.Mask" "F.Paste")
			(net "GND")
		)
	)
	(footprint ""
		(layer "F.Cu")
		(at 327.281032 -13.746734)
		(property "Reference" "C535"
			(at 0 0 0)
			(layer "F.SilkS")
			(hide yes)
			(effects
				(font
					(size 1.27 1.27)
				)
			)
		)
		(property "Value" ""
			(at 0 0 0)
			(layer "F.Fab")
			(effects
				(font
					(size 1.27 1.27)
				)
			)
		)
		(duplicate_pad_numbers_are_jumpers no)
		(fp_line
			(start -1.524 -0.762)
			(end 1.524 -0.762)
			(stroke
				(width 0.1524)
				(type default)
			)
			(layer "F.SilkS")
		)
		(fp_line
			(start -1.524 0.762)
			(end -1.524 -0.762)
			(stroke
				(width 0.1524)
				(type default)
			)
			(layer "F.SilkS")
		)
		(fp_line
			(start 1.524 -0.762)
			(end 1.524 0.762)
			(stroke
				(width 0.1524)
				(type default)
			)
			(layer "F.SilkS")
		)
		(fp_line
			(start 1.524 0.762)
			(end -1.524 0.762)
			(stroke
				(width 0.1524)
				(type default)
			)
			(layer "F.SilkS")
		)
		(fp_line
			(start -1.1049 -0.724916)
			(end -1.1049 0.724916)
			(stroke
				(width 0.1)
				(type default)
			)
			(layer "F.Fab")
		)
		(fp_line
			(start -1.1049 0.724916)
			(end 1.1049 0.724916)
			(stroke
				(width 0.1)
				(type default)
			)
			(layer "F.Fab")
		)
		(fp_line
			(start 1.1049 -0.724916)
			(end -1.1049 -0.724916)
			(stroke
				(width 0.1)
				(type default)
			)
			(layer "F.Fab")
		)
		(fp_line
			(start 1.1049 0.724916)
			(end 1.1049 -0.724916)
			(stroke
				(width 0.1)
				(type default)
			)
			(layer "F.Fab")
		)
		(pad "1" smd rect
			(at -0.889 0 180)
			(size 1.016 1.27)
			(layers "F.Cu" "F.Mask" "F.Paste")
			(net "PGPPA_AUX")
		)
		(pad "2" smd rect
			(at 0.889 0 180)
			(size 1.016 1.27)
			(layers "F.Cu" "F.Mask" "F.Paste")
			(net "GND")
		)
	)
)
